(kicad_pcb
	(version 20260206)
	(generator "pcbnew")
	(generator_version "10.0")
	(general
		(thickness 1.6)
		(legacy_teardrops no)
	)
	(paper "A4")
	(title_block
		(title "netronome-mezz — pcbd0082-001_rev01_jul9_a.brd")
		(comment 1 "Open CloudServer (Microsoft) / footprints 322-332 of 714")
	)
	(layers
		(0 "F.Cu" signal "TOP")
		(4 "In1.Cu" signal "02_GND")
		(6 "In2.Cu" signal "03_SIG")
		(8 "In3.Cu" signal "04_SIG")
		(10 "In4.Cu" signal "05_GND")
		(12 "In5.Cu" signal "06_PWR1")
		(14 "In6.Cu" signal "07_SIG")
		(16 "In7.Cu" signal "08_SIG")
		(18 "In8.Cu" signal "09_GND")
		(2 "B.Cu" signal "BOTTOM")
		(9 "F.Adhes" user "F.Adhesive")
		(11 "B.Adhes" user "B.Adhesive")
		(13 "F.Paste" user "Package Geometry/Pastemask Top")
		(15 "B.Paste" user "Package Geometry/Pastemask Bottom")
		(5 "F.SilkS" user "Ref Des/Silkscreen Top")
		(7 "B.SilkS" user "Ref Des/Silkscreen Bottom")
		(1 "F.Mask" user "Board Geometry/Soldermask Top")
		(3 "B.Mask" user "Board Geometry/Soldermask Bottom")
		(17 "Dwgs.User" user "User.Drawings")
		(19 "Cmts.User" user "User.Comments")
		(21 "Eco1.User" user "User.Eco1")
		(23 "Eco2.User" user "User.Eco2")
		(25 "Edge.Cuts" user "Board Geometry/Outline")
		(27 "Margin" user)
		(31 "F.CrtYd" user "Package Geometry/Place Bound Top")
		(29 "B.CrtYd" user "Package Geometry/Place Bound Bottom")
		(35 "F.Fab" user "Ref Des/Assembly Top")
		(33 "B.Fab" user "Ref Des/Assembly Bottom")
		(45 "User.4" user "COMPVAL_TYPE_BOTTOM")
	)
	(footprint ""
		(layer "B.Cu")
		(at 62.737238 34.042096 90)
		(property "Reference" "R170"
			(at 0 0 90)
			(layer "B.SilkS")
			(hide yes)
			(effects
				(font
					(size 1.27 1.27)
				)
				(justify mirror)
			)
		)
		(property "Value" ""
			(at 0 0 90)
			(layer "B.Fab")
			(effects
				(font
					(size 1.27 1.27)
				)
				(justify mirror)
			)
		)
		(duplicate_pad_numbers_are_jumpers no)
		(fp_circle
			(center 0 0)
			(end 0 0.104648)
			(stroke
				(width 0.1016)
				(type default)
			)
			(fill no)
			(layer "B.SilkS")
		)
		(fp_poly
			(pts
				(xy 0.381 -0.889) (xy 0.381 0.889) (xy -0.381 0.889) (xy -0.381 -0.889)
			)
			(stroke
				(width 0)
				(type default)
			)
			(fill no)
			(layer "B.CrtYd")
		)
		(fp_line
			(start 0.508 -1.016)
			(end 0.254 -1.016)
			(stroke
				(width 0.0254)
				(type default)
			)
			(layer "B.Fab")
		)
		(fp_line
			(start 0.254 -1.016)
			(end -0.508 -1.016)
			(stroke
				(width 0.0254)
				(type default)
			)
			(layer "B.Fab")
		)
		(fp_line
			(start -0.508 -1.016)
			(end -0.508 1.016)
			(stroke
				(width 0.0254)
				(type default)
			)
			(layer "B.Fab")
		)
		(fp_line
			(start 0.508 1.016)
			(end 0.508 -1.016)
			(stroke
				(width 0.0254)
				(type default)
			)
			(layer "B.Fab")
		)
		(fp_line
			(start -0.508 1.016)
			(end 0.508 1.016)
			(stroke
				(width 0.0254)
				(type default)
			)
			(layer "B.Fab")
		)
		(pad "1" smd custom
			(at 0 -0.500126 270)
			(size 0.127 0.127)
			(layers "B.Cu" "B.Mask" "B.Paste")
			(net "VR_OD1_L")
			(options
				(clearance outline)
				(anchor circle)
			)
			(primitives
				(gr_poly
					(pts
						(xy -0.1778 0.254) (xy 0.1778 0.254) (xy 0.254 0.1778) (xy 0.254 -0.1778) (xy 0.1778 -0.254) (xy -0.1778 -0.254)
						(xy -0.254 -0.1778) (xy -0.254 0.1778)
					)
					(width 0)
					(fill yes)
				)
			)
		)
		(pad "2" smd custom
			(at 0 0.500126 270)
			(size 0.127 0.127)
			(layers "B.Cu" "B.Mask" "B.Paste")
			(net "10N2230")
			(options
				(clearance outline)
				(anchor circle)
			)
			(primitives
				(gr_poly
					(pts
						(xy -0.1778 0.254) (xy 0.1778 0.254) (xy 0.254 0.1778) (xy 0.254 -0.1778) (xy 0.1778 -0.254) (xy -0.1778 -0.254)
						(xy -0.254 -0.1778) (xy -0.254 0.1778)
					)
					(width 0)
					(fill yes)
				)
			)
		)
	)
	(footprint ""
		(layer "B.Cu")
		(at 79.450997 2.699004)
		(property "Reference" "V1_A-CAS"
			(at 0 0 0)
			(layer "B.SilkS")
			(hide yes)
			(effects
				(font
					(size 1.27 1.27)
				)
				(justify mirror)
			)
		)
		(property "Value" ""
			(at 0 0 0)
			(layer "B.Fab")
			(effects
				(font
					(size 1.27 1.27)
				)
				(justify mirror)
			)
		)
		(duplicate_pad_numbers_are_jumpers no)
		(pad "1" thru_hole circle
			(at 0 0 180)
			(size 0.4572 0.4572)
			(drill 0.20574)
			(layers "*.Cu" "*.Mask")
			(remove_unused_layers no)
			(net "DDR0_32A_CAS_L")
			(clearance 0.1143)
			(thermal_gap 0.1143)
		)
	)
	(footprint ""
		(layer "B.Cu")
		(at 54.737 8.291297 -90)
		(property "Reference" "L2"
			(at -1.433297 0.02667 270)
			(unlocked yes)
			(layer "B.SilkS")
			(effects
				(font
					(size 0.7874 0.5842)
					(thickness 0.127)
				)
				(justify left mirror)
			)
		)
		(property "Value" ""
			(at 0 0 90)
			(layer "B.Fab")
			(effects
				(font
					(size 1.27 1.27)
				)
				(justify mirror)
			)
		)
		(duplicate_pad_numbers_are_jumpers no)
		(fp_rect
			(start -1.7907 0.889)
			(end 1.7907 -0.889)
			(stroke
				(width 0)
				(type default)
			)
			(fill no)
			(layer "B.CrtYd")
		)
		(fp_line
			(start -1.778 0.762)
			(end 1.778 0.762)
			(stroke
				(width 0.0254)
				(type default)
			)
			(layer "B.Fab")
		)
		(fp_line
			(start 1.778 0.762)
			(end 1.778 -0.762)
			(stroke
				(width 0.0254)
				(type default)
			)
			(layer "B.Fab")
		)
		(fp_line
			(start -1.778 -0.762)
			(end -1.778 0.762)
			(stroke
				(width 0.0254)
				(type default)
			)
			(layer "B.Fab")
		)
		(fp_line
			(start 1.778 -0.762)
			(end -1.778 -0.762)
			(stroke
				(width 0.0254)
				(type default)
			)
			(layer "B.Fab")
		)
		(pad "1" smd rect
			(at 0.7493 0)
			(size 0.7874 0.8128)
			(layers "B.Cu" "B.Mask" "B.Paste")
			(net "VDD_CORE")
		)
		(pad "2" smd rect
			(at -0.7493 0)
			(size 0.7874 0.8128)
			(layers "B.Cu" "B.Mask" "B.Paste")
			(net "VDDA_PCIE0")
		)
		(zone
			(layer "B.Cu")
			(hatch none 0.5)
			(connect_pads
				(clearance 0)
			)
			(min_thickness 0.25)
			(keepout
				(tracks not_allowed)
				(vias allowed)
				(pads allowed)
				(copperpour not_allowed)
				(footprints allowed)
			)
			(placement
				(enabled no)
				(sheetname "")
			)
			(fill
				(thermal_gap 0.5)
				(thermal_bridge_width 0.5)
				(island_removal_mode 0)
			)
			(polygon
				(pts
					(xy 55.1434 8.570697) (xy 54.3306 8.570697) (xy 54.3306 8.011897) (xy 55.1434 8.011897)
				)
			)
		)
	)
	(footprint ""
		(layer "B.Cu")
		(at 82.8548 42.9006 90)
		(property "Reference" "C31"
			(at -0.68707 3.2512 0)
			(unlocked yes)
			(layer "B.SilkS")
			(effects
				(font
					(size 0.7874 0.5842)
					(thickness 0.127)
				)
				(justify left mirror)
			)
		)
		(property "Value" "0.01UF"
			(at 0.091846 0.2921 0)
			(unlocked yes)
			(layer "B.Fab")
			(hide yes)
			(effects
				(font
					(size 0.7874 0.5842)
					(thickness 0.2032)
				)
				(justify left mirror)
			)
		)
		(property "Device Type" "CAPC1553"
			(at 0.091846 0.2921 0)
			(unlocked yes)
			(layer "B.Fab")
			(hide yes)
			(effects
				(font
					(size 0.7874 0.5842)
					(thickness 0.2032)
				)
				(justify left mirror)
			)
		)
		(duplicate_pad_numbers_are_jumpers no)
		(fp_poly
			(pts
				(xy -0.635 1.0668) (xy -0.635 -1.0668) (xy 0.635 -1.0668) (xy 0.635 1.0668)
			)
			(stroke
				(width 0)
				(type default)
			)
			(fill no)
			(layer "B.CrtYd")
		)
		(fp_line
			(start 0.254 -0.508)
			(end -0.254 -0.508)
			(stroke
				(width 0.0254)
				(type default)
			)
			(layer "B.Fab")
		)
		(fp_line
			(start -0.254 -0.508)
			(end -0.254 0.508)
			(stroke
				(width 0.0254)
				(type default)
			)
			(layer "B.Fab")
		)
		(fp_line
			(start 0.254 0.508)
			(end 0.254 -0.508)
			(stroke
				(width 0.0254)
				(type default)
			)
			(layer "B.Fab")
		)
		(fp_line
			(start -0.254 0.508)
			(end 0.254 0.508)
			(stroke
				(width 0.0254)
				(type default)
			)
			(layer "B.Fab")
		)
		(pad "1" smd rect
			(at 0 -0.4191 270)
			(size 0.508 0.5334)
			(layers "B.Cu" "B.Mask" "B.Paste")
			(net "11N2146")
		)
		(pad "2" smd rect
			(at 0 0.4191 270)
			(size 0.508 0.5334)
			(layers "B.Cu" "B.Mask" "B.Paste")
			(net "GND")
		)
		(zone
			(layer "B.Cu")
			(hatch none 0.5)
			(connect_pads
				(clearance 0)
			)
			(min_thickness 0.25)
			(keepout
				(tracks not_allowed)
				(vias allowed)
				(pads allowed)
				(copperpour not_allowed)
				(footprints allowed)
			)
			(placement
				(enabled no)
				(sheetname "")
			)
			(fill
				(thermal_gap 0.5)
				(thermal_bridge_width 0.5)
				(island_removal_mode 0)
			)
			(polygon
				(pts
					(xy 82.8294 42.926) (xy 82.8802 42.926) (xy 82.8802 42.8752) (xy 82.8294 42.8752)
				)
			)
		)
	)
	(footprint ""
		(layer "B.Cu")
		(at 59.236991 31.541974)
		(property "Reference" "C168"
			(at 1.061339 -0.299974 270)
			(unlocked yes)
			(layer "B.SilkS")
			(effects
				(font
					(size 0.7874 0.5842)
					(thickness 0.127)
				)
				(justify mirror)
			)
		)
		(property "Value" ""
			(at 0 0 0)
			(layer "B.Fab")
			(effects
				(font
					(size 1.27 1.27)
				)
				(justify mirror)
			)
		)
		(duplicate_pad_numbers_are_jumpers no)
		(fp_circle
			(center 0 0)
			(end 0.104648 0)
			(stroke
				(width 0.1016)
				(type default)
			)
			(fill no)
			(layer "B.SilkS")
		)
		(fp_poly
			(pts
				(xy 0.381 -0.889) (xy 0.381 0.889) (xy -0.381 0.889) (xy -0.381 -0.889)
			)
			(stroke
				(width 0)
				(type default)
			)
			(fill no)
			(layer "B.CrtYd")
		)
		(fp_line
			(start -0.508 -1.016)
			(end -0.508 1.016)
			(stroke
				(width 0.0254)
				(type default)
			)
			(layer "B.Fab")
		)
		(fp_line
			(start -0.508 1.016)
			(end 0.508 1.016)
			(stroke
				(width 0.0254)
				(type default)
			)
			(layer "B.Fab")
		)
		(fp_line
			(start 0.254 -1.016)
			(end -0.508 -1.016)
			(stroke
				(width 0.0254)
				(type default)
			)
			(layer "B.Fab")
		)
		(fp_line
			(start 0.508 -1.016)
			(end 0.254 -1.016)
			(stroke
				(width 0.0254)
				(type default)
			)
			(layer "B.Fab")
		)
		(fp_line
			(start 0.508 1.016)
			(end 0.508 -1.016)
			(stroke
				(width 0.0254)
				(type default)
			)
			(layer "B.Fab")
		)
		(pad "1" smd custom
			(at 0 -0.500126 180)
			(size 0.127 0.127)
			(layers "B.Cu" "B.Mask" "B.Paste")
			(net "VDD_CORE")
			(options
				(clearance outline)
				(anchor circle)
			)
			(primitives
				(gr_poly
					(pts
						(xy -0.1778 0.254) (xy 0.1778 0.254) (xy 0.254 0.1778) (xy 0.254 -0.1778) (xy 0.1778 -0.254) (xy -0.1778 -0.254)
						(xy -0.254 -0.1778) (xy -0.254 0.1778)
					)
					(width 0)
					(fill yes)
				)
			)
		)
		(pad "2" smd custom
			(at 0 0.500126 180)
			(size 0.127 0.127)
			(layers "B.Cu" "B.Mask" "B.Paste")
			(net "GND")
			(options
				(clearance outline)
				(anchor circle)
			)
			(primitives
				(gr_poly
					(pts
						(xy -0.1778 0.254) (xy 0.1778 0.254) (xy 0.254 0.1778) (xy 0.254 -0.1778) (xy 0.1778 -0.254) (xy -0.1778 -0.254)
						(xy -0.254 -0.1778) (xy -0.254 0.1778)
					)
					(width 0)
					(fill yes)
				)
			)
		)
	)
	(footprint ""
		(layer "B.Cu")
		(at 76.251003 2.699004)
		(property "Reference" "V_A-DQS0-N"
			(at 0 0 0)
			(layer "B.SilkS")
			(hide yes)
			(effects
				(font
					(size 1.27 1.27)
				)
				(justify mirror)
			)
		)
		(property "Value" ""
			(at 0 0 0)
			(layer "B.Fab")
			(effects
				(font
					(size 1.27 1.27)
				)
				(justify mirror)
			)
		)
		(duplicate_pad_numbers_are_jumpers no)
		(pad "1" thru_hole circle
			(at 0 0 180)
			(size 0.4572 0.4572)
			(drill 0.20574)
			(layers "*.Cu" "*.Mask")
			(remove_unused_layers no)
			(net "DDR0_32A_DQS0_N")
			(clearance 0.1143)
			(thermal_gap 0.1143)
		)
	)
	(footprint ""
		(layer "B.Cu")
		(at 49.237011 25.541986 180)
		(property "Reference" "C175"
			(at 0.495681 2.935986 270)
			(unlocked yes)
			(layer "B.SilkS")
			(effects
				(font
					(size 0.7874 0.5842)
					(thickness 0.127)
				)
				(justify mirror)
			)
		)
		(property "Value" ""
			(at 0 0 0)
			(layer "B.Fab")
			(effects
				(font
					(size 1.27 1.27)
				)
				(justify mirror)
			)
		)
		(duplicate_pad_numbers_are_jumpers no)
		(fp_circle
			(center 0 0)
			(end -0.104648 0)
			(stroke
				(width 0.1016)
				(type default)
			)
			(fill no)
			(layer "B.SilkS")
		)
		(fp_poly
			(pts
				(xy 0.381 -0.889) (xy 0.381 0.889) (xy -0.381 0.889) (xy -0.381 -0.889)
			)
			(stroke
				(width 0)
				(type default)
			)
			(fill no)
			(layer "B.CrtYd")
		)
		(fp_line
			(start 0.508 1.016)
			(end 0.508 -1.016)
			(stroke
				(width 0.0254)
				(type default)
			)
			(layer "B.Fab")
		)
		(fp_line
			(start 0.508 -1.016)
			(end 0.254 -1.016)
			(stroke
				(width 0.0254)
				(type default)
			)
			(layer "B.Fab")
		)
		(fp_line
			(start 0.254 -1.016)
			(end -0.508 -1.016)
			(stroke
				(width 0.0254)
				(type default)
			)
			(layer "B.Fab")
		)
		(fp_line
			(start -0.508 1.016)
			(end 0.508 1.016)
			(stroke
				(width 0.0254)
				(type default)
			)
			(layer "B.Fab")
		)
		(fp_line
			(start -0.508 -1.016)
			(end -0.508 1.016)
			(stroke
				(width 0.0254)
				(type default)
			)
			(layer "B.Fab")
		)
		(pad "1" smd custom
			(at 0 -0.500126)
			(size 0.127 0.127)
			(layers "B.Cu" "B.Mask" "B.Paste")
			(net "VDD_CORE")
			(options
				(clearance outline)
				(anchor circle)
			)
			(primitives
				(gr_poly
					(pts
						(xy -0.1778 0.254) (xy 0.1778 0.254) (xy 0.254 0.1778) (xy 0.254 -0.1778) (xy 0.1778 -0.254) (xy -0.1778 -0.254)
						(xy -0.254 -0.1778) (xy -0.254 0.1778)
					)
					(width 0)
					(fill yes)
				)
			)
		)
		(pad "2" smd custom
			(at 0 0.500126)
			(size 0.127 0.127)
			(layers "B.Cu" "B.Mask" "B.Paste")
			(net "GND")
			(options
				(clearance outline)
				(anchor circle)
			)
			(primitives
				(gr_poly
					(pts
						(xy -0.1778 0.254) (xy 0.1778 0.254) (xy 0.254 0.1778) (xy 0.254 -0.1778) (xy 0.1778 -0.254) (xy -0.1778 -0.254)
						(xy -0.254 -0.1778) (xy -0.254 0.1778)
					)
					(width 0)
					(fill yes)
				)
			)
		)
	)
	(footprint ""
		(layer "B.Cu")
		(at 80.250995 14.256004)
		(property "Reference" "V2_A-WE"
			(at 0 0 0)
			(layer "B.SilkS")
			(hide yes)
			(effects
				(font
					(size 1.27 1.27)
				)
				(justify mirror)
			)
		)
		(property "Value" ""
			(at 0 0 0)
			(layer "B.Fab")
			(effects
				(font
					(size 1.27 1.27)
				)
				(justify mirror)
			)
		)
		(duplicate_pad_numbers_are_jumpers no)
		(pad "1" thru_hole circle
			(at 0 0 180)
			(size 0.4572 0.4572)
			(drill 0.20574)
			(layers "*.Cu" "*.Mask")
			(remove_unused_layers no)
			(net "DDR0_32A_WE_L")
			(clearance 0.1143)
			(thermal_gap 0.1143)
		)
	)
	(footprint ""
		(layer "B.Cu")
		(at 30.988 7.493)
		(property "Reference" "C84"
			(at -1.42367 1.143 270)
			(unlocked yes)
			(layer "B.SilkS")
			(effects
				(font
					(size 0.7874 0.5842)
					(thickness 0.127)
				)
				(justify left mirror)
			)
		)
		(property "Value" "0.1UF"
			(at 0.091846 0.2921 270)
			(unlocked yes)
			(layer "B.Fab")
			(hide yes)
			(effects
				(font
					(size 0.7874 0.5842)
					(thickness 0.2032)
				)
				(justify left mirror)
			)
		)
		(property "Device Type" "CAPC0073"
			(at 0.091846 0.2921 270)
			(unlocked yes)
			(layer "B.Fab")
			(hide yes)
			(effects
				(font
					(size 0.7874 0.5842)
					(thickness 0.2032)
				)
				(justify left mirror)
			)
		)
		(duplicate_pad_numbers_are_jumpers no)
		(fp_poly
			(pts
				(xy -0.635 1.0668) (xy -0.635 -1.0668) (xy 0.635 -1.0668) (xy 0.635 1.0668)
			)
			(stroke
				(width 0)
				(type default)
			)
			(fill no)
			(layer "B.CrtYd")
		)
		(fp_line
			(start -0.254 -0.508)
			(end -0.254 0.508)
			(stroke
				(width 0.0254)
				(type default)
			)
			(layer "B.Fab")
		)
		(fp_line
			(start -0.254 0.508)
			(end 0.254 0.508)
			(stroke
				(width 0.0254)
				(type default)
			)
			(layer "B.Fab")
		)
		(fp_line
			(start 0.254 -0.508)
			(end -0.254 -0.508)
			(stroke
				(width 0.0254)
				(type default)
			)
			(layer "B.Fab")
		)
		(fp_line
			(start 0.254 0.508)
			(end 0.254 -0.508)
			(stroke
				(width 0.0254)
				(type default)
			)
			(layer "B.Fab")
		)
		(pad "1" smd rect
			(at 0 -0.4191 180)
			(size 0.508 0.5334)
			(layers "B.Cu" "B.Mask" "B.Paste")
			(net "EXT_3.3V")
		)
		(pad "2" smd rect
			(at 0 0.4191 180)
			(size 0.508 0.5334)
			(layers "B.Cu" "B.Mask" "B.Paste")
			(net "GND")
		)
		(zone
			(layer "B.Cu")
			(hatch none 0.5)
			(connect_pads
				(clearance 0)
			)
			(min_thickness 0.25)
			(keepout
				(tracks not_allowed)
				(vias allowed)
				(pads allowed)
				(copperpour not_allowed)
				(footprints allowed)
			)
			(placement
				(enabled no)
				(sheetname "")
			)
			(fill
				(thermal_gap 0.5)
				(thermal_bridge_width 0.5)
				(island_removal_mode 0)
			)
			(polygon
				(pts
					(xy 30.9626 7.4676) (xy 30.9626 7.5184) (xy 31.0134 7.5184) (xy 31.0134 7.4676)
				)
			)
		)
	)
	(footprint ""
		(layer "B.Cu")
		(at 75.451005 29.812996)
		(property "Reference" "V_A-CB5"
			(at 0 0 0)
			(layer "B.SilkS")
			(hide yes)
			(effects
				(font
					(size 1.27 1.27)
				)
				(justify mirror)
			)
		)
		(property "Value" ""
			(at 0 0 0)
			(layer "B.Fab")
			(effects
				(font
					(size 1.27 1.27)
				)
				(justify mirror)
			)
		)
		(duplicate_pad_numbers_are_jumpers no)
		(pad "1" thru_hole circle
			(at 0 0 180)
			(size 0.4572 0.4572)
			(drill 0.20574)
			(layers "*.Cu" "*.Mask")
			(remove_unused_layers no)
			(net "DDR0_32A_CB5")
			(clearance 0.1143)
			(thermal_gap 0.1143)
		)
	)
	(footprint ""
		(layer "B.Cu")
		(at 62.236985 10.542016 180)
		(property "Reference" "C116"
			(at 0 0 0)
			(layer "B.SilkS")
			(hide yes)
			(effects
				(font
					(size 1.27 1.27)
				)
				(justify mirror)
			)
		)
		(property "Value" ""
			(at 0 0 0)
			(layer "B.Fab")
			(effects
				(font
					(size 1.27 1.27)
				)
				(justify mirror)
			)
		)
		(duplicate_pad_numbers_are_jumpers no)
		(fp_circle
			(center 0 0)
			(end -0.104648 0)
			(stroke
				(width 0.1016)
				(type default)
			)
			(fill no)
			(layer "B.SilkS")
		)
		(fp_poly
			(pts
				(xy 0.381 -0.889) (xy 0.381 0.889) (xy -0.381 0.889) (xy -0.381 -0.889)
			)
			(stroke
				(width 0)
				(type default)
			)
			(fill no)
			(layer "B.CrtYd")
		)
		(fp_line
			(start 0.508 1.016)
			(end 0.508 -1.016)
			(stroke
				(width 0.0254)
				(type default)
			)
			(layer "B.Fab")
		)
		(fp_line
			(start 0.508 -1.016)
			(end 0.254 -1.016)
			(stroke
				(width 0.0254)
				(type default)
			)
			(layer "B.Fab")
		)
		(fp_line
			(start 0.254 -1.016)
			(end -0.508 -1.016)
			(stroke
				(width 0.0254)
				(type default)
			)
			(layer "B.Fab")
		)
		(fp_line
			(start -0.508 1.016)
			(end 0.508 1.016)
			(stroke
				(width 0.0254)
				(type default)
			)
			(layer "B.Fab")
		)
		(fp_line
			(start -0.508 -1.016)
			(end -0.508 1.016)
			(stroke
				(width 0.0254)
				(type default)
			)
			(layer "B.Fab")
		)
		(pad "1" smd custom
			(at 0 -0.500126)
			(size 0.127 0.127)
			(layers "B.Cu" "B.Mask" "B.Paste")
			(net "VDDA_DDR0_32A")
			(options
				(clearance outline)
				(anchor circle)
			)
			(primitives
				(gr_poly
					(pts
						(xy -0.1778 0.254) (xy 0.1778 0.254) (xy 0.254 0.1778) (xy 0.254 -0.1778) (xy 0.1778 -0.254) (xy -0.1778 -0.254)
						(xy -0.254 -0.1778) (xy -0.254 0.1778)
					)
					(width 0)
					(fill yes)
				)
			)
		)
		(pad "2" smd custom
			(at 0 0.500126)
			(size 0.127 0.127)
			(layers "B.Cu" "B.Mask" "B.Paste")
			(net "GND")
			(options
				(clearance outline)
				(anchor circle)
			)
			(primitives
				(gr_poly
					(pts
						(xy -0.1778 0.254) (xy 0.1778 0.254) (xy 0.254 0.1778) (xy 0.254 -0.1778) (xy 0.1778 -0.254) (xy -0.1778 -0.254)
						(xy -0.254 -0.1778) (xy -0.254 0.1778)
					)
					(width 0)
					(fill yes)
				)
			)
		)
	)
)
